(kicad_pcb
	(version 20260206)
	(generator "pcbnew")
	(generator_version "10.0")
	(general
		(thickness 1.6)
		(legacy_teardrops no)
	)
	(paper "A4")
	(title_block
		(title "04192023_DAF0TMB3IC0_F0TG_MB_C_brd_V02_OCP.brd")
		(comment 1 "Grand Teton / footprints 8353-8354 of 8354")
	)
	(layers
		(0 "F.Cu" signal "TOP")
		(4 "In1.Cu" signal "GND")
		(6 "In2.Cu" signal "IN1")
		(8 "In3.Cu" signal "GND1")
		(10 "In4.Cu" signal "IN2")
		(12 "In5.Cu" signal "GND2")
		(14 "In6.Cu" signal "IN3")
		(16 "In7.Cu" signal "GND3")
		(18 "In8.Cu" signal "VCC")
		(20 "In9.Cu" signal "VCC1")
		(22 "In10.Cu" signal "GND4")
		(24 "In11.Cu" signal "IN4")
		(26 "In12.Cu" signal "GND5")
		(28 "In13.Cu" signal "IN5")
		(30 "In14.Cu" signal "GND6")
		(32 "In15.Cu" signal "IN6")
		(34 "In16.Cu" signal "GND7")
		(2 "B.Cu" signal "BOTTOM")
		(9 "F.Adhes" user "F.Adhesive")
		(11 "B.Adhes" user "B.Adhesive")
		(13 "F.Paste" user "Package Geometry/Pastemask Top")
		(15 "B.Paste" user "Package Geometry/Pastemask Bottom")
		(5 "F.SilkS" user "Ref Des/Silkscreen Top")
		(7 "B.SilkS" user "Ref Des/Silkscreen Bottom")
		(1 "F.Mask" user "Board Geometry/Soldermask Top")
		(3 "B.Mask" user "Board Geometry/Soldermask Bottom")
		(17 "Dwgs.User" user "User.Drawings")
		(19 "Cmts.User" user "User.Comments")
		(21 "Eco1.User" user "User.Eco1")
		(23 "Eco2.User" user "User.Eco2")
		(25 "Edge.Cuts" user "Board Geometry/Outline")
		(27 "Margin" user)
		(31 "F.CrtYd" user "Package Geometry/Place Bound Top")
		(29 "B.CrtYd" user "Package Geometry/Place Bound Bottom")
		(35 "F.Fab" user "Ref Des/Assembly Top")
		(33 "B.Fab" user "Ref Des/Assembly Bottom")
	)
	(footprint ""
		(layer "B.Cu")
		(at 129.20218 -37.09543 -90)
		(property "Reference" "C6063"
			(at 0 0 90)
			(layer "B.SilkS")
			(hide yes)
			(effects
				(font
					(size 1.27 1.27)
				)
				(justify mirror)
			)
		)
		(property "Value" ""
			(at 0 0 90)
			(layer "B.Fab")
			(effects
				(font
					(size 1.27 1.27)
				)
				(justify mirror)
			)
		)
		(duplicate_pad_numbers_are_jumpers no)
		(fp_line
			(start -0.7874 0.4064)
			(end 0.7874 0.4064)
			(stroke
				(width 0.1524)
				(type default)
			)
			(layer "B.SilkS")
		)
		(fp_line
			(start 0.7874 0.4064)
			(end 0.7874 -0.4064)
			(stroke
				(width 0.1524)
				(type default)
			)
			(layer "B.SilkS")
		)
		(fp_line
			(start -0.7874 -0.4064)
			(end -0.7874 0.4064)
			(stroke
				(width 0.1524)
				(type default)
			)
			(layer "B.SilkS")
		)
		(fp_line
			(start 0.7874 -0.4064)
			(end -0.7874 -0.4064)
			(stroke
				(width 0.1524)
				(type default)
			)
			(layer "B.SilkS")
		)
		(fp_line
			(start -0.67945 0.3048)
			(end -0.120396 0.3048)
			(stroke
				(width 0.1)
				(type default)
			)
			(layer "B.Fab")
		)
		(fp_line
			(start -0.120396 0.3048)
			(end -0.120396 0.2794)
			(stroke
				(width 0.1)
				(type default)
			)
			(layer "B.Fab")
		)
		(fp_line
			(start 0.12065 0.3048)
			(end 0.67945 0.3048)
			(stroke
				(width 0.1)
				(type default)
			)
			(layer "B.Fab")
		)
		(fp_line
			(start 0.67945 0.3048)
			(end 0.67945 -0.305054)
			(stroke
				(width 0.1)
				(type default)
			)
			(layer "B.Fab")
		)
		(fp_line
			(start -0.120396 0.2794)
			(end 0.12065 0.2794)
			(stroke
				(width 0.1)
				(type default)
			)
			(layer "B.Fab")
		)
		(fp_line
			(start 0.12065 0.2794)
			(end 0.12065 0.3048)
			(stroke
				(width 0.1)
				(type default)
			)
			(layer "B.Fab")
		)
		(fp_line
			(start -0.12065 -0.2794)
			(end -0.12065 -0.3048)
			(stroke
				(width 0.1)
				(type default)
			)
			(layer "B.Fab")
		)
		(fp_line
			(start 0.12065 -0.2794)
			(end -0.12065 -0.2794)
			(stroke
				(width 0.1)
				(type default)
			)
			(layer "B.Fab")
		)
		(fp_line
			(start -0.67945 -0.3048)
			(end -0.67945 0.3048)
			(stroke
				(width 0.1)
				(type default)
			)
			(layer "B.Fab")
		)
		(fp_line
			(start -0.12065 -0.3048)
			(end -0.67945 -0.3048)
			(stroke
				(width 0.1)
				(type default)
			)
			(layer "B.Fab")
		)
		(fp_line
			(start 0.12065 -0.305054)
			(end 0.12065 -0.2794)
			(stroke
				(width 0.1)
				(type default)
			)
			(layer "B.Fab")
		)
		(fp_line
			(start 0.67945 -0.305054)
			(end 0.12065 -0.305054)
			(stroke
				(width 0.1)
				(type default)
			)
			(layer "B.Fab")
		)
		(pad "1" smd circle
			(at 0.40005 0 90)
			(size 0 0)
			(layers "B.Cu" "B.Mask" "B.Paste")
			(net "P1V2_AUX")
		)
		(pad "2" smd circle
			(at -0.40005 0 90)
			(size 0 0)
			(layers "B.Cu" "B.Mask" "B.Paste")
			(net "GND")
		)
	)
	(footprint ""
		(layer "B.Cu")
		(at 426.53585 -33.467548 180)
		(property "Reference" "R744"
			(at 0 0 0)
			(layer "B.SilkS")
			(hide yes)
			(effects
				(font
					(size 1.27 1.27)
				)
				(justify mirror)
			)
		)
		(property "Value" ""
			(at 0 0 0)
			(layer "B.Fab")
			(effects
				(font
					(size 1.27 1.27)
				)
				(justify mirror)
			)
		)
		(duplicate_pad_numbers_are_jumpers no)
		(fp_line
			(start 0.7874 0.4064)
			(end 0.7874 -0.4064)
			(stroke
				(width 0.1524)
				(type default)
			)
			(layer "B.SilkS")
		)
		(fp_line
			(start 0.7874 -0.4064)
			(end -0.7874 -0.4064)
			(stroke
				(width 0.1524)
				(type default)
			)
			(layer "B.SilkS")
		)
		(fp_line
			(start -0.7874 0.4064)
			(end 0.7874 0.4064)
			(stroke
				(width 0.1524)
				(type default)
			)
			(layer "B.SilkS")
		)
		(fp_line
			(start -0.7874 -0.4064)
			(end -0.7874 0.4064)
			(stroke
				(width 0.1524)
				(type default)
			)
			(layer "B.SilkS")
		)
		(fp_line
			(start 0.67945 0.3048)
			(end 0.67945 -0.305054)
			(stroke
				(width 0.1)
				(type default)
			)
			(layer "B.Fab")
		)
		(fp_line
			(start 0.67945 -0.305054)
			(end 0.12065 -0.305054)
			(stroke
				(width 0.1)
				(type default)
			)
			(layer "B.Fab")
		)
		(fp_line
			(start 0.12065 0.3048)
			(end 0.67945 0.3048)
			(stroke
				(width 0.1)
				(type default)
			)
			(layer "B.Fab")
		)
		(fp_line
			(start 0.12065 0.2794)
			(end 0.12065 0.3048)
			(stroke
				(width 0.1)
				(type default)
			)
			(layer "B.Fab")
		)
		(fp_line
			(start 0.12065 -0.2794)
			(end -0.12065 -0.2794)
			(stroke
				(width 0.1)
				(type default)
			)
			(layer "B.Fab")
		)
		(fp_line
			(start 0.12065 -0.305054)
			(end 0.12065 -0.2794)
			(stroke
				(width 0.1)
				(type default)
			)
			(layer "B.Fab")
		)
		(fp_line
			(start -0.120396 0.3048)
			(end -0.120396 0.2794)
			(stroke
				(width 0.1)
				(type default)
			)
			(layer "B.Fab")
		)
		(fp_line
			(start -0.120396 0.2794)
			(end 0.12065 0.2794)
			(stroke
				(width 0.1)
				(type default)
			)
			(layer "B.Fab")
		)
		(fp_line
			(start -0.12065 -0.2794)
			(end -0.12065 -0.3048)
			(stroke
				(width 0.1)
				(type default)
			)
			(layer "B.Fab")
		)
		(fp_line
			(start -0.12065 -0.3048)
			(end -0.67945 -0.3048)
			(stroke
				(width 0.1)
				(type default)
			)
			(layer "B.Fab")
		)
		(fp_line
			(start -0.67945 0.3048)
			(end -0.120396 0.3048)
			(stroke
				(width 0.1)
				(type default)
			)
			(layer "B.Fab")
		)
		(fp_line
			(start -0.67945 -0.3048)
			(end -0.67945 0.3048)
			(stroke
				(width 0.1)
				(type default)
			)
			(layer "B.Fab")
		)
		(pad "1" smd circle
			(at 0.40005 0)
			(size 0 0)
			(layers "B.Cu" "B.Mask" "B.Paste")
			(net "PRSNT_CPU1_N")
		)
		(pad "2" smd circle
			(at -0.40005 0)
			(size 0 0)
			(layers "B.Cu" "B.Mask" "B.Paste")
			(net "FM_PRSNT_CPU1_N")
		)
	)
)
